# S9S_MB_2U (Grand Teton) — schematic netlist excerpt (pin names and nets, part order shuffled) for the footprints in the layout excerpt that follows; sources: Cadence DE-HDL packaged netlist, KiCad conversion of 03242023_DA0F0TMBIJ0_F0T_Motherboard_J_brd_V01_OCP.brd

R1338  Q_RES  10K 1% CHIP  pkg 0402LF  page 201 : A = FM_PCH_BIOS_RCVR_MODE ; B = GND
R4140  Q_RES  4.7K 5% CHIP  pkg 0402LF  page 146 : A = P3V3_AUX ; B = GPU_3V3IO_RSVD3_FFU_ISO

(kicad_pcb
	(version 20260206)
	(generator "pcbnew")
	(generator_version "10.0")
	(general
		(thickness 1.6)
		(legacy_teardrops no)
	)
	(paper "A4")
	(title_block
		(title "03242023_DA0F0TMBIJ0_F0T_Motherboard_J_brd_V01_OCP.brd")
		(comment 1 "Grand Teton / footprints 277-278 of 6105")
	)
	(layers
		(0 "F.Cu" signal "TOP")
		(4 "In1.Cu" signal "GND")
		(6 "In2.Cu" signal "IN1")
		(8 "In3.Cu" signal "GND1")
		(10 "In4.Cu" signal "IN2")
		(12 "In5.Cu" signal "GND2")
		(14 "In6.Cu" signal "IN3")
		(16 "In7.Cu" signal "GND3")
		(18 "In8.Cu" signal "VCC")
		(20 "In9.Cu" signal "VCC1")
		(22 "In10.Cu" signal "GND4")
		(24 "In11.Cu" signal "IN4")
		(26 "In12.Cu" signal "GND5")
		(28 "In13.Cu" signal "IN5")
		(30 "In14.Cu" signal "GND6")
		(32 "In15.Cu" signal "IN6")
		(34 "In16.Cu" signal "GND7")
		(2 "B.Cu" signal "BOTTOM")
		(9 "F.Adhes" user "F.Adhesive")
		(11 "B.Adhes" user "B.Adhesive")
		(13 "F.Paste" user "Package Geometry/Pastemask Top")
		(15 "B.Paste" user "Package Geometry/Pastemask Bottom")
		(5 "F.SilkS" user "Ref Des/Silkscreen Top")
		(7 "B.SilkS" user "Ref Des/Silkscreen Bottom")
		(1 "F.Mask" user "Board Geometry/Soldermask Top")
		(3 "B.Mask" user "Board Geometry/Soldermask Bottom")
		(17 "Dwgs.User" user "User.Drawings")
		(19 "Cmts.User" user "User.Comments")
		(21 "Eco1.User" user "User.Eco1")
		(23 "Eco2.User" user "User.Eco2")
		(25 "Edge.Cuts" user "Board Geometry/Outline")
		(27 "Margin" user)
		(31 "F.CrtYd" user "Package Geometry/Place Bound Top")
		(29 "B.CrtYd" user "Package Geometry/Place Bound Bottom")
		(35 "F.Fab" user "Ref Des/Assembly Top")
		(33 "B.Fab" user "Ref Des/Assembly Bottom")
	)
	(footprint ""
		(layer "F.Cu")
		(at 307.14188 -50.878486 180)
		(property "Reference" "R1338"
			(at 0 0 180)
			(layer "F.SilkS")
			(hide yes)
			(effects
				(font
					(size 1.27 1.27)
				)
			)
		)
		(property "Value" ""
			(at 0 0 180)
			(layer "F.Fab")
			(effects
				(font
					(size 1.27 1.27)
				)
			)
		)
		(duplicate_pad_numbers_are_jumpers no)
		(fp_line
			(start 0.7874 0.4064)
			(end -0.7874 0.4064)
			(stroke
				(width 0.1524)
				(type default)
			)
			(layer "F.SilkS")
		)
		(fp_line
			(start 0.7874 -0.4064)
			(end 0.7874 0.4064)
			(stroke
				(width 0.1524)
				(type default)
			)
			(layer "F.SilkS")
		)
		(fp_line
			(start -0.7874 0.4064)
			(end -0.7874 -0.4064)
			(stroke
				(width 0.1524)
				(type default)
			)
			(layer "F.SilkS")
		)
		(fp_line
			(start -0.7874 -0.4064)
			(end 0.7874 -0.4064)
			(stroke
				(width 0.1524)
				(type default)
			)
			(layer "F.SilkS")
		)
		(fp_line
			(start 0.67945 0.3048)
			(end 0.120396 0.3048)
			(stroke
				(width 0.1)
				(type default)
			)
			(layer "F.Fab")
		)
		(fp_line
			(start 0.67945 -0.3048)
			(end 0.67945 0.3048)
			(stroke
				(width 0.1)
				(type default)
			)
			(layer "F.Fab")
		)
		(fp_line
			(start 0.12065 -0.2794)
			(end 0.12065 -0.3048)
			(stroke
				(width 0.1)
				(type default)
			)
			(layer "F.Fab")
		)
		(fp_line
			(start 0.12065 -0.3048)
			(end 0.67945 -0.3048)
			(stroke
				(width 0.1)
				(type default)
			)
			(layer "F.Fab")
		)
		(fp_line
			(start 0.120396 0.3048)
			(end 0.120396 0.2794)
			(stroke
				(width 0.1)
				(type default)
			)
			(layer "F.Fab")
		)
		(fp_line
			(start 0.120396 0.2794)
			(end -0.12065 0.2794)
			(stroke
				(width 0.1)
				(type default)
			)
			(layer "F.Fab")
		)
		(fp_line
			(start -0.12065 0.3048)
			(end -0.67945 0.3048)
			(stroke
				(width 0.1)
				(type default)
			)
			(layer "F.Fab")
		)
		(fp_line
			(start -0.12065 0.2794)
			(end -0.12065 0.3048)
			(stroke
				(width 0.1)
				(type default)
			)
			(layer "F.Fab")
		)
		(fp_line
			(start -0.12065 -0.2794)
			(end 0.12065 -0.2794)
			(stroke
				(width 0.1)
				(type default)
			)
			(layer "F.Fab")
		)
		(fp_line
			(start -0.12065 -0.305054)
			(end -0.12065 -0.2794)
			(stroke
				(width 0.1)
				(type default)
			)
			(layer "F.Fab")
		)
		(fp_line
			(start -0.67945 0.3048)
			(end -0.67945 -0.305054)
			(stroke
				(width 0.1)
				(type default)
			)
			(layer "F.Fab")
		)
		(fp_line
			(start -0.67945 -0.305054)
			(end -0.12065 -0.305054)
			(stroke
				(width 0.1)
				(type default)
			)
			(layer "F.Fab")
		)
		(pad "1" smd circle
			(at -0.40005 0 180)
			(size 0 0)
			(layers "F.Cu" "F.Mask" "F.Paste")
			(net "FM_PCH_BIOS_RCVR_MODE")
		)
		(pad "2" smd circle
			(at 0.40005 0 180)
			(size 0 0)
			(layers "F.Cu" "F.Mask" "F.Paste")
			(net "GND")
		)
	)
	(footprint ""
		(layer "F.Cu")
		(at 304.09896 -433.04587 90)
		(property "Reference" "R4140"
			(at 0 0 90)
			(layer "F.SilkS")
			(hide yes)
			(effects
				(font
					(size 1.27 1.27)
				)
			)
		)
		(property "Value" ""
			(at 0 0 90)
			(layer "F.Fab")
			(effects
				(font
					(size 1.27 1.27)
				)
			)
		)
		(duplicate_pad_numbers_are_jumpers no)
		(fp_line
			(start 0.7874 -0.4064)
			(end 0.7874 0.4064)
			(stroke
				(width 0.1524)
				(type default)
			)
			(layer "F.SilkS")
		)
		(fp_line
			(start -0.7874 -0.4064)
			(end 0.7874 -0.4064)
			(stroke
				(width 0.1524)
				(type default)
			)
			(layer "F.SilkS")
		)
		(fp_line
			(start 0.7874 0.4064)
			(end -0.7874 0.4064)
			(stroke
				(width 0.1524)
				(type default)
			)
			(layer "F.SilkS")
		)
		(fp_line
			(start -0.7874 0.4064)
			(end -0.7874 -0.4064)
			(stroke
				(width 0.1524)
				(type default)
			)
			(layer "F.SilkS")
		)
		(fp_line
			(start -0.12065 -0.305054)
			(end -0.12065 -0.2794)
			(stroke
				(width 0.1)
				(type default)
			)
			(layer "F.Fab")
		)
		(fp_line
			(start -0.67945 -0.305054)
			(end -0.12065 -0.305054)
			(stroke
				(width 0.1)
				(type default)
			)
			(layer "F.Fab")
		)
		(fp_line
			(start 0.67945 -0.3048)
			(end 0.67945 0.3048)
			(stroke
				(width 0.1)
				(type default)
			)
			(layer "F.Fab")
		)
		(fp_line
			(start 0.12065 -0.3048)
			(end 0.67945 -0.3048)
			(stroke
				(width 0.1)
				(type default)
			)
			(layer "F.Fab")
		)
		(fp_line
			(start 0.12065 -0.2794)
			(end 0.12065 -0.3048)
			(stroke
				(width 0.1)
				(type default)
			)
			(layer "F.Fab")
		)
		(fp_line
			(start -0.12065 -0.2794)
			(end 0.12065 -0.2794)
			(stroke
				(width 0.1)
				(type default)
			)
			(layer "F.Fab")
		)
		(fp_line
			(start 0.120396 0.2794)
			(end -0.12065 0.2794)
			(stroke
				(width 0.1)
				(type default)
			)
			(layer "F.Fab")
		)
		(fp_line
			(start -0.12065 0.2794)
			(end -0.12065 0.3048)
			(stroke
				(width 0.1)
				(type default)
			)
			(layer "F.Fab")
		)
		(fp_line
			(start 0.67945 0.3048)
			(end 0.120396 0.3048)
			(stroke
				(width 0.1)
				(type default)
			)
			(layer "F.Fab")
		)
		(fp_line
			(start 0.120396 0.3048)
			(end 0.120396 0.2794)
			(stroke
				(width 0.1)
				(type default)
			)
			(layer "F.Fab")
		)
		(fp_line
			(start -0.12065 0.3048)
			(end -0.67945 0.3048)
			(stroke
				(width 0.1)
				(type default)
			)
			(layer "F.Fab")
		)
		(fp_line
			(start -0.67945 0.3048)
			(end -0.67945 -0.305054)
			(stroke
				(width 0.1)
				(type default)
			)
			(layer "F.Fab")
		)
		(pad "1" smd circle
			(at -0.40005 0 90)
			(size 0 0)
			(layers "F.Cu" "F.Mask" "F.Paste")
			(net "P3V3_AUX")
		)
		(pad "2" smd circle
			(at 0.40005 0 90)
			(size 0 0)
			(layers "F.Cu" "F.Mask" "F.Paste")
			(net "GPU_3V3IO_RSVD3_FFU_ISO")
		)
	)
)
